(kicad_pcb
	(version 20260206)
	(generator "pcbnew")
	(generator_version "10.0")
	(general
		(thickness 1.6)
		(legacy_teardrops no)
	)
	(paper "A4")
	(title_block
		(title "panther-plus-userver — 13130-1b_20150205.brd")
		(comment 1 "Honey Badger (Wiwynn) / footprints 942-949 of 1509")
	)
	(layers
		(0 "F.Cu" signal "TOP")
		(4 "In1.Cu" signal "L2")
		(6 "In2.Cu" signal "L3")
		(8 "In3.Cu" signal "L4")
		(10 "In4.Cu" signal "L5")
		(12 "In5.Cu" signal "L6")
		(14 "In6.Cu" signal "L7")
		(16 "In7.Cu" signal "L8")
		(18 "In8.Cu" signal "L9")
		(20 "In9.Cu" signal "L10")
		(22 "In10.Cu" signal "L11")
		(2 "B.Cu" signal "BOTTOM")
		(9 "F.Adhes" user "F.Adhesive")
		(11 "B.Adhes" user "B.Adhesive")
		(13 "F.Paste" user "Package Geometry/Pastemask Top")
		(15 "B.Paste" user "Package Geometry/Pastemask Bottom")
		(5 "F.SilkS" user "Ref Des/Silkscreen Top")
		(7 "B.SilkS" user "Ref Des/Silkscreen Bottom")
		(1 "F.Mask" user "Board Geometry/Soldermask Top")
		(3 "B.Mask" user "Board Geometry/Soldermask Bottom")
		(17 "Dwgs.User" user "User.Drawings")
		(19 "Cmts.User" user "User.Comments")
		(21 "Eco1.User" user "User.Eco1")
		(23 "Eco2.User" user "User.Eco2")
		(25 "Edge.Cuts" user "Board Geometry/Outline")
		(27 "Margin" user)
		(31 "F.CrtYd" user "Package Geometry/Place Bound Top")
		(29 "B.CrtYd" user "Package Geometry/Place Bound Bottom")
		(35 "F.Fab" user "Ref Des/Assembly Top")
		(33 "B.Fab" user "Ref Des/Assembly Bottom")
	)
	(footprint ""
		(layer "B.Cu")
		(at 80.01 -37.592 -90)
		(property "Reference" "R334"
			(at 0 0 90)
			(layer "B.SilkS")
			(hide yes)
			(effects
				(font
					(size 1.27 1.27)
				)
				(justify mirror)
			)
		)
		(property "Value" "33R2F-3-GP"
			(at -0.064008 -3.993896 270)
			(unlocked yes)
			(layer "B.Fab")
			(hide yes)
			(effects
				(font
					(size 1.016 1.016)
					(thickness 0.1524)
				)
				(justify mirror)
			)
		)
		(property "Device Type" "R402H16"
			(at -0.064008 -5.517896 270)
			(unlocked yes)
			(layer "B.Fab")
			(hide yes)
			(effects
				(font
					(size 1.016 1.016)
					(thickness 0.1524)
				)
				(justify mirror)
			)
		)
		(duplicate_pad_numbers_are_jumpers no)
		(fp_rect
			(start 0.381 0.8382)
			(end -0.381 -0.8382)
			(stroke
				(width 0)
				(type default)
			)
			(fill no)
			(layer "B.CrtYd")
		)
		(fp_rect
			(start 0.381 0.8382)
			(end -0.381 -0.8382)
			(stroke
				(width 0)
				(type default)
			)
			(fill no)
			(layer "B.Fab")
		)
		(pad "1" smd custom
			(at 0 -0.4318 90)
			(size 0.127 0.127)
			(layers "B.Cu" "B.Mask" "B.Paste")
			(net "PMU_SUS_CLK_CPU")
			(options
				(clearance outline)
				(anchor circle)
			)
			(primitives
				(gr_poly
					(pts
						(arc
							(start -0.2032 0.2794)
							(mid -0.239121 0.264521)
							(end -0.254 0.2286)
						)
						(arc
							(start -0.254 -0.2286)
							(mid -0.239121 -0.264521)
							(end -0.2032 -0.2794)
						)
						(arc
							(start 0.2032 -0.2794)
							(mid 0.239121 -0.264521)
							(end 0.254 -0.2286)
						)
						(arc
							(start 0.254 0.2286)
							(mid 0.239121 0.264521)
							(end 0.2032 0.2794)
						)
					)
					(width 0)
					(fill yes)
				)
			)
		)
		(pad "2" smd custom
			(at 0 0.4318 90)
			(size 0.127 0.127)
			(layers "B.Cu" "B.Mask" "B.Paste")
			(net "PMU_SUS_CLK")
			(options
				(clearance outline)
				(anchor circle)
			)
			(primitives
				(gr_poly
					(pts
						(arc
							(start -0.2032 0.2794)
							(mid -0.239121 0.264521)
							(end -0.254 0.2286)
						)
						(arc
							(start -0.254 -0.2286)
							(mid -0.239121 -0.264521)
							(end -0.2032 -0.2794)
						)
						(arc
							(start 0.2032 -0.2794)
							(mid 0.239121 -0.264521)
							(end 0.254 -0.2286)
						)
						(arc
							(start 0.254 0.2286)
							(mid 0.239121 0.264521)
							(end 0.2032 0.2794)
						)
					)
					(width 0)
					(fill yes)
				)
			)
		)
	)
	(footprint ""
		(layer "B.Cu")
		(at 16.764 -34.417 90)
		(property "Reference" "PR189"
			(at 0 0 90)
			(layer "B.SilkS")
			(hide yes)
			(effects
				(font
					(size 1.27 1.27)
				)
				(justify mirror)
			)
		)
		(property "Value" "0R2J-2-GP"
			(at -1.7907 -1.1176 90)
			(unlocked yes)
			(layer "B.Fab")
			(hide yes)
			(effects
				(font
					(size 1.016 1.016)
					(thickness 0.1524)
				)
				(justify mirror)
			)
		)
		(property "Device Type" "R402H16"
			(at -1.7907 -2.6416 90)
			(unlocked yes)
			(layer "B.Fab")
			(hide yes)
			(effects
				(font
					(size 1.016 1.016)
					(thickness 0.1524)
				)
				(justify mirror)
			)
		)
		(duplicate_pad_numbers_are_jumpers no)
		(fp_rect
			(start 0.381 0.8382)
			(end -0.381 -0.8382)
			(stroke
				(width 0)
				(type default)
			)
			(fill no)
			(layer "B.CrtYd")
		)
		(fp_rect
			(start 0.381 0.8382)
			(end -0.381 -0.8382)
			(stroke
				(width 0)
				(type default)
			)
			(fill no)
			(layer "B.Fab")
		)
		(pad "1" smd custom
			(at 0 -0.4318 270)
			(size 0.127 0.127)
			(layers "B.Cu" "B.Mask" "B.Paste")
			(net "P3V3_STBY_ROVP")
			(options
				(clearance outline)
				(anchor circle)
			)
			(primitives
				(gr_poly
					(pts
						(arc
							(start -0.2032 0.2794)
							(mid -0.239121 0.264521)
							(end -0.254 0.2286)
						)
						(arc
							(start -0.254 -0.2286)
							(mid -0.239121 -0.264521)
							(end -0.2032 -0.2794)
						)
						(arc
							(start 0.2032 -0.2794)
							(mid 0.239121 -0.264521)
							(end 0.254 -0.2286)
						)
						(arc
							(start 0.254 0.2286)
							(mid 0.239121 0.264521)
							(end 0.2032 0.2794)
						)
					)
					(width 0)
					(fill yes)
				)
			)
		)
		(pad "2" smd custom
			(at 0 0.4318 270)
			(size 0.127 0.127)
			(layers "B.Cu" "B.Mask" "B.Paste")
			(net "AGND_P3V3_STBY")
			(options
				(clearance outline)
				(anchor circle)
			)
			(primitives
				(gr_poly
					(pts
						(arc
							(start -0.2032 0.2794)
							(mid -0.239121 0.264521)
							(end -0.254 0.2286)
						)
						(arc
							(start -0.254 -0.2286)
							(mid -0.239121 -0.264521)
							(end -0.2032 -0.2794)
						)
						(arc
							(start 0.2032 -0.2794)
							(mid 0.239121 -0.264521)
							(end 0.254 -0.2286)
						)
						(arc
							(start 0.254 0.2286)
							(mid 0.239121 0.264521)
							(end 0.2032 0.2794)
						)
					)
					(width 0)
					(fill yes)
				)
			)
		)
	)
	(footprint ""
		(layer "B.Cu")
		(at 103.3018 -43.958002 90)
		(property "Reference" "C163"
			(at 0 0 90)
			(layer "B.SilkS")
			(hide yes)
			(effects
				(font
					(size 1.27 1.27)
				)
				(justify mirror)
			)
		)
		(property "Value" "SC1U10V2KX-1GP"
			(at -1.1811 -2.7051 90)
			(unlocked yes)
			(layer "B.Fab")
			(hide yes)
			(effects
				(font
					(size 1.016 1.016)
					(thickness 0.1524)
				)
				(justify mirror)
			)
		)
		(property "Device Type" "C402H22"
			(at -1.1811 -4.2291 90)
			(unlocked yes)
			(layer "B.Fab")
			(hide yes)
			(effects
				(font
					(size 1.016 1.016)
					(thickness 0.1524)
				)
				(justify mirror)
			)
		)
		(duplicate_pad_numbers_are_jumpers no)
		(fp_rect
			(start 0.381 0.7366)
			(end -0.381 -0.7366)
			(stroke
				(width 0)
				(type default)
			)
			(fill no)
			(layer "B.CrtYd")
		)
		(fp_rect
			(start 0.381 0.7366)
			(end -0.381 -0.7366)
			(stroke
				(width 0)
				(type default)
			)
			(fill no)
			(layer "B.Fab")
		)
		(pad "1" smd custom
			(at 0 -0.4572 270)
			(size 0.1143 0.1143)
			(layers "B.Cu" "B.Mask" "B.Paste")
			(net "P1V0")
			(options
				(clearance outline)
				(anchor circle)
			)
			(primitives
				(gr_poly
					(pts
						(arc
							(start -0.254 0.1778)
							(mid -0.239121 0.213721)
							(end -0.2032 0.2286)
						)
						(arc
							(start 0.2032 0.2286)
							(mid 0.239121 0.213721)
							(end 0.254 0.1778)
						)
						(arc
							(start 0.254 -0.1778)
							(mid 0.239121 -0.213721)
							(end 0.2032 -0.2286)
						)
						(arc
							(start -0.2032 -0.2286)
							(mid -0.239121 -0.213721)
							(end -0.254 -0.1778)
						)
					)
					(width 0)
					(fill yes)
				)
			)
		)
		(pad "2" smd custom
			(at 0 0.4572 270)
			(size 0.1143 0.1143)
			(layers "B.Cu" "B.Mask" "B.Paste")
			(net "GND")
			(options
				(clearance outline)
				(anchor circle)
			)
			(primitives
				(gr_poly
					(pts
						(arc
							(start -0.254 0.1778)
							(mid -0.239121 0.213721)
							(end -0.2032 0.2286)
						)
						(arc
							(start 0.2032 0.2286)
							(mid 0.239121 0.213721)
							(end 0.254 0.1778)
						)
						(arc
							(start 0.254 -0.1778)
							(mid 0.239121 -0.213721)
							(end 0.2032 -0.2286)
						)
						(arc
							(start -0.2032 -0.2286)
							(mid -0.239121 -0.213721)
							(end -0.254 -0.1778)
						)
					)
					(width 0)
					(fill yes)
				)
			)
		)
	)
	(footprint ""
		(layer "B.Cu")
		(at 74.041 -32.512 90)
		(property "Reference" "R367"
			(at 0 0 90)
			(layer "B.SilkS")
			(hide yes)
			(effects
				(font
					(size 1.27 1.27)
				)
				(justify mirror)
			)
		)
		(property "Value" "1KR2F-3-GP"
			(at -1.7907 -1.1176 90)
			(unlocked yes)
			(layer "B.Fab")
			(hide yes)
			(effects
				(font
					(size 1.016 1.016)
					(thickness 0.1524)
				)
				(justify mirror)
			)
		)
		(property "Device Type" "R402H16"
			(at -1.7907 -2.6416 90)
			(unlocked yes)
			(layer "B.Fab")
			(hide yes)
			(effects
				(font
					(size 1.016 1.016)
					(thickness 0.1524)
				)
				(justify mirror)
			)
		)
		(duplicate_pad_numbers_are_jumpers no)
		(fp_rect
			(start 0.381 0.8382)
			(end -0.381 -0.8382)
			(stroke
				(width 0)
				(type default)
			)
			(fill no)
			(layer "B.CrtYd")
		)
		(fp_rect
			(start 0.381 0.8382)
			(end -0.381 -0.8382)
			(stroke
				(width 0)
				(type default)
			)
			(fill no)
			(layer "B.Fab")
		)
		(pad "1" smd custom
			(at 0 -0.4318 270)
			(size 0.127 0.127)
			(layers "B.Cu" "B.Mask" "B.Paste")
			(net "P3V3_CPU")
			(options
				(clearance outline)
				(anchor circle)
			)
			(primitives
				(gr_poly
					(pts
						(arc
							(start -0.2032 0.2794)
							(mid -0.239121 0.264521)
							(end -0.254 0.2286)
						)
						(arc
							(start -0.254 -0.2286)
							(mid -0.239121 -0.264521)
							(end -0.2032 -0.2794)
						)
						(arc
							(start 0.2032 -0.2794)
							(mid 0.239121 -0.264521)
							(end 0.254 -0.2286)
						)
						(arc
							(start 0.254 0.2286)
							(mid 0.239121 0.264521)
							(end 0.2032 0.2794)
						)
					)
					(width 0)
					(fill yes)
				)
			)
		)
		(pad "2" smd custom
			(at 0 0.4318 270)
			(size 0.127 0.127)
			(layers "B.Cu" "B.Mask" "B.Paste")
			(net "GBE_WOL")
			(options
				(clearance outline)
				(anchor circle)
			)
			(primitives
				(gr_poly
					(pts
						(arc
							(start -0.2032 0.2794)
							(mid -0.239121 0.264521)
							(end -0.254 0.2286)
						)
						(arc
							(start -0.254 -0.2286)
							(mid -0.239121 -0.264521)
							(end -0.2032 -0.2794)
						)
						(arc
							(start 0.2032 -0.2794)
							(mid 0.239121 -0.264521)
							(end 0.254 -0.2286)
						)
						(arc
							(start 0.254 0.2286)
							(mid 0.239121 0.264521)
							(end 0.2032 0.2794)
						)
					)
					(width 0)
					(fill yes)
				)
			)
		)
	)
	(footprint ""
		(layer "B.Cu")
		(at 39.116 -30.48 180)
		(property "Reference" "C114"
			(at 0 0 0)
			(layer "B.SilkS")
			(hide yes)
			(effects
				(font
					(size 1.27 1.27)
				)
				(justify mirror)
			)
		)
		(property "Value" "SC1U10V2KX-1GP"
			(at -1.1811 -2.7051 180)
			(unlocked yes)
			(layer "B.Fab")
			(hide yes)
			(effects
				(font
					(size 1.016 1.016)
					(thickness 0.1524)
				)
				(justify mirror)
			)
		)
		(property "Device Type" "C402H22"
			(at -1.1811 -4.2291 180)
			(unlocked yes)
			(layer "B.Fab")
			(hide yes)
			(effects
				(font
					(size 1.016 1.016)
					(thickness 0.1524)
				)
				(justify mirror)
			)
		)
		(duplicate_pad_numbers_are_jumpers no)
		(fp_rect
			(start 0.381 0.7366)
			(end -0.381 -0.7366)
			(stroke
				(width 0)
				(type default)
			)
			(fill no)
			(layer "B.CrtYd")
		)
		(fp_rect
			(start 0.381 0.7366)
			(end -0.381 -0.7366)
			(stroke
				(width 0)
				(type default)
			)
			(fill no)
			(layer "B.Fab")
		)
		(pad "1" smd custom
			(at 0 -0.4572)
			(size 0.1143 0.1143)
			(layers "B.Cu" "B.Mask" "B.Paste")
			(net "P1V0")
			(options
				(clearance outline)
				(anchor circle)
			)
			(primitives
				(gr_poly
					(pts
						(arc
							(start -0.254 0.1778)
							(mid -0.239121 0.213721)
							(end -0.2032 0.2286)
						)
						(arc
							(start 0.2032 0.2286)
							(mid 0.239121 0.213721)
							(end 0.254 0.1778)
						)
						(arc
							(start 0.254 -0.1778)
							(mid 0.239121 -0.213721)
							(end 0.2032 -0.2286)
						)
						(arc
							(start -0.2032 -0.2286)
							(mid -0.239121 -0.213721)
							(end -0.254 -0.1778)
						)
					)
					(width 0)
					(fill yes)
				)
			)
		)
		(pad "2" smd custom
			(at 0 0.4572)
			(size 0.1143 0.1143)
			(layers "B.Cu" "B.Mask" "B.Paste")
			(net "GND")
			(options
				(clearance outline)
				(anchor circle)
			)
			(primitives
				(gr_poly
					(pts
						(arc
							(start -0.254 0.1778)
							(mid -0.239121 0.213721)
							(end -0.2032 0.2286)
						)
						(arc
							(start 0.2032 0.2286)
							(mid 0.239121 0.213721)
							(end 0.254 0.1778)
						)
						(arc
							(start 0.254 -0.1778)
							(mid 0.239121 -0.213721)
							(end 0.2032 -0.2286)
						)
						(arc
							(start -0.2032 -0.2286)
							(mid -0.239121 -0.213721)
							(end -0.254 -0.1778)
						)
					)
					(width 0)
					(fill yes)
				)
			)
		)
	)
	(footprint ""
		(layer "B.Cu")
		(at 76.835 -18.1864 -90)
		(property "Reference" "PC198"
			(at 0 0 90)
			(layer "B.SilkS")
			(hide yes)
			(effects
				(font
					(size 1.27 1.27)
				)
				(justify mirror)
			)
		)
		(property "Value" "SC10U6D3V5KX-4GP"
			(at 0.0762 -6.1214 270)
			(unlocked yes)
			(layer "B.Fab")
			(hide yes)
			(effects
				(font
					(size 1.016 1.016)
					(thickness 0.1524)
				)
				(justify mirror)
			)
		)
		(property "Device Type" "C805H58"
			(at 0.0762 -8.1534 270)
			(unlocked yes)
			(layer "B.Fab")
			(hide yes)
			(effects
				(font
					(size 1.016 1.016)
					(thickness 0.1524)
				)
				(justify mirror)
			)
		)
		(duplicate_pad_numbers_are_jumpers no)
		(fp_line
			(start -0.6096 0)
			(end 0.6096 0)
			(stroke
				(width 0.3048)
				(type default)
			)
			(layer "B.SilkS")
		)
		(fp_poly
			(pts
				(xy 0.9017 1.4351) (xy -0.9017 1.4351) (xy -0.9017 -1.4351) (xy 0.9017 -1.4351)
			)
			(stroke
				(width 0)
				(type default)
			)
			(fill no)
			(layer "B.CrtYd")
		)
		(fp_poly
			(pts
				(xy -0.9017 1.4351) (xy -0.9017 -1.4351) (xy 0.9017 -1.4351) (xy 0.9017 1.4351)
			)
			(stroke
				(width 0)
				(type default)
			)
			(fill no)
			(layer "B.Fab")
		)
		(pad "1" smd rect
			(at 0 -0.8382 90)
			(size 1.5494 0.9398)
			(layers "B.Cu" "B.Mask" "B.Paste")
			(net "TPS74801_P1V35_IN")
		)
		(pad "2" smd rect
			(at 0 0.8382 90)
			(size 1.5494 0.9398)
			(layers "B.Cu" "B.Mask" "B.Paste")
			(net "GND")
		)
	)
	(footprint ""
		(layer "B.Cu")
		(at 197.7136 -60.452 -90)
		(property "Reference" "PC163"
			(at 0 0 90)
			(layer "B.SilkS")
			(hide yes)
			(effects
				(font
					(size 1.27 1.27)
				)
				(justify mirror)
			)
		)
		(property "Value" "SC22U6D3V5MX-2GP"
			(at 0 -4.9022 270)
			(unlocked yes)
			(layer "B.Fab")
			(hide yes)
			(effects
				(font
					(size 1.016 1.016)
					(thickness 0.1524)
				)
				(justify mirror)
			)
		)
		(property "Device Type" "C805H58"
			(at 0 -6.8072 270)
			(unlocked yes)
			(layer "B.Fab")
			(hide yes)
			(effects
				(font
					(size 1.016 1.016)
					(thickness 0.1524)
				)
				(justify mirror)
			)
		)
		(duplicate_pad_numbers_are_jumpers no)
		(fp_line
			(start -0.6096 0)
			(end 0.6096 0)
			(stroke
				(width 0.3048)
				(type default)
			)
			(layer "B.SilkS")
		)
		(fp_poly
			(pts
				(xy 0.9017 1.4351) (xy -0.9017 1.4351) (xy -0.9017 -1.4351) (xy 0.9017 -1.4351)
			)
			(stroke
				(width 0)
				(type default)
			)
			(fill no)
			(layer "B.CrtYd")
		)
		(fp_poly
			(pts
				(xy -0.9017 1.4351) (xy -0.9017 -1.4351) (xy 0.9017 -1.4351) (xy 0.9017 1.4351)
			)
			(stroke
				(width 0)
				(type default)
			)
			(fill no)
			(layer "B.Fab")
		)
		(pad "1" smd rect
			(at 0 -0.8382 90)
			(size 1.5494 0.9398)
			(layers "B.Cu" "B.Mask" "B.Paste")
			(net "PV_VDDR")
		)
		(pad "2" smd rect
			(at 0 0.8382 90)
			(size 1.5494 0.9398)
			(layers "B.Cu" "B.Mask" "B.Paste")
			(net "GND")
		)
	)
	(footprint ""
		(layer "B.Cu")
		(at 69.215 -62.865 90)
		(property "Reference" "R172"
			(at 0 0 90)
			(layer "B.SilkS")
			(hide yes)
			(effects
				(font
					(size 1.27 1.27)
				)
				(justify mirror)
			)
		)
		(property "Value" "10KR2F-2-GP"
			(at -1.7907 -1.1176 90)
			(unlocked yes)
			(layer "B.Fab")
			(hide yes)
			(effects
				(font
					(size 1.016 1.016)
					(thickness 0.1524)
				)
				(justify mirror)
			)
		)
		(property "Device Type" "R402H16"
			(at -1.7907 -2.6416 90)
			(unlocked yes)
			(layer "B.Fab")
			(hide yes)
			(effects
				(font
					(size 1.016 1.016)
					(thickness 0.1524)
				)
				(justify mirror)
			)
		)
		(duplicate_pad_numbers_are_jumpers no)
		(fp_rect
			(start 0.381 0.8382)
			(end -0.381 -0.8382)
			(stroke
				(width 0)
				(type default)
			)
			(fill no)
			(layer "B.CrtYd")
		)
		(fp_rect
			(start 0.381 0.8382)
			(end -0.381 -0.8382)
			(stroke
				(width 0)
				(type default)
			)
			(fill no)
			(layer "B.Fab")
		)
		(pad "1" smd custom
			(at 0 -0.4318 270)
			(size 0.127 0.127)
			(layers "B.Cu" "B.Mask" "B.Paste")
			(net "P12V")
			(options
				(clearance outline)
				(anchor circle)
			)
			(primitives
				(gr_poly
					(pts
						(arc
							(start -0.2032 0.2794)
							(mid -0.239121 0.264521)
							(end -0.254 0.2286)
						)
						(arc
							(start -0.254 -0.2286)
							(mid -0.239121 -0.264521)
							(end -0.2032 -0.2794)
						)
						(arc
							(start 0.2032 -0.2794)
							(mid 0.239121 -0.264521)
							(end 0.254 -0.2286)
						)
						(arc
							(start 0.254 0.2286)
							(mid 0.239121 0.264521)
							(end 0.2032 0.2794)
						)
					)
					(width 0)
					(fill yes)
				)
			)
		)
		(pad "2" smd custom
			(at 0 0.4318 270)
			(size 0.127 0.127)
			(layers "B.Cu" "B.Mask" "B.Paste")
			(net "P12V_SENSE")
			(options
				(clearance outline)
				(anchor circle)
			)
			(primitives
				(gr_poly
					(pts
						(arc
							(start -0.2032 0.2794)
							(mid -0.239121 0.264521)
							(end -0.254 0.2286)
						)
						(arc
							(start -0.254 -0.2286)
							(mid -0.239121 -0.264521)
							(end -0.2032 -0.2794)
						)
						(arc
							(start 0.2032 -0.2794)
							(mid 0.239121 -0.264521)
							(end 0.254 -0.2286)
						)
						(arc
							(start 0.254 0.2286)
							(mid 0.239121 0.264521)
							(end 0.2032 0.2794)
						)
					)
					(width 0)
					(fill yes)
				)
			)
		)
	)
)
